(kicad_pcb
	(version 20241229)
	(generator "pcbnew")
	(generator_version "9.0")
	(general
		(thickness 1.6642)
		(legacy_teardrops no)
	)
	(paper "A3")
	(title_block
		(title "PolarFire SoM")
		(date "2025-07-22")
		(rev "1.1.4")
		(company "Antmicro Ltd")
		(comment 1 "www.antmicro.com")
		(comment 9 "footprints 61-64 of 470")
	)
	(layers
		(0 "F.Cu" mixed)
		(4 "In1.Cu" power)
		(6 "In2.Cu" signal)
		(8 "In3.Cu" power)
		(10 "In4.Cu" signal)
		(12 "In5.Cu" power)
		(14 "In6.Cu" power)
		(16 "In7.Cu" signal)
		(18 "In8.Cu" power)
		(20 "In9.Cu" signal)
		(22 "In10.Cu" power)
		(24 "In11.Cu" signal)
		(26 "In12.Cu" signal)
		(2 "B.Cu" mixed)
		(9 "F.Adhes" user "F.Adhesive")
		(11 "B.Adhes" user "B.Adhesive")
		(13 "F.Paste" user)
		(15 "B.Paste" user)
		(5 "F.SilkS" user "F.Silkscreen")
		(7 "B.SilkS" user "B.Silkscreen")
		(1 "F.Mask" user)
		(3 "B.Mask" user)
		(17 "Dwgs.User" user "User.Drawings")
		(19 "Cmts.User" user "User.Comments")
		(21 "Eco1.User" user "User.Eco1")
		(23 "Eco2.User" user "User.Eco2")
		(25 "Edge.Cuts" user)
		(27 "Margin" user)
		(31 "F.CrtYd" user "F.Courtyard")
		(29 "B.CrtYd" user "B.Courtyard")
		(35 "F.Fab" user)
		(33 "B.Fab" user)
	)
	(footprint "antmicro-footprints:LED_1204_3210Metric_RGB_Horizontal"
		(layer "F.Cu")
		(at 228.675 126.749999 90)
		(descr "Footprint based on: https://optoelectronics.liteon.com/upload/download/DS22-2003-047/LTST-S310F2KT.PDF")
		(property "Reference" "D6"
			(at 0 -1.695 90)
			(unlocked yes)
			(layer "F.SilkS")
			(effects
				(font
					(size 0.7 0.7)
					(thickness 0.15)
				)
				(justify left bottom)
			)
		)
		(property "Value" "LED_RGB_1204_LTST-S310F2KT_Horizontal"
			(at 0 2.195 90)
			(unlocked yes)
			(layer "F.Fab")
			(hide yes)
			(effects
				(font
					(size 0.7 0.7)
					(thickness 0.15)
				)
				(justify left bottom)
			)
		)
		(property "Datasheet" "https://optoelectronics.liteon.com/upload/download/DS22-2003-047/LTST-S310F2KT.PDF"
			(at 0 0 90)
			(layer "F.Fab")
			(hide yes)
			(effects
				(font
					(size 0.7 0.7)
					(thickness 0.15)
				)
				(justify left bottom)
			)
		)
		(property "Description" "LED, RGB, SMD, 1204, R 30 mA, G 20 mA, B 20 mA, R 2 V, G 3.5 V, B 3.5 V, Common Anode, Side Look"
			(at 0 0 90)
			(layer "F.Fab")
			(hide yes)
			(effects
				(font
					(size 0.7 0.7)
					(thickness 0.15)
				)
				(justify left bottom)
			)
		)
		(property "MPN" "LTST-S310F2KT"
			(at 0 0 90)
			(unlocked yes)
			(layer "F.Fab")
			(hide yes)
			(effects
				(font
					(size 1 1)
					(thickness 0.15)
				)
			)
		)
		(property "Manufacturer" "Lite-On"
			(at 0 0 90)
			(unlocked yes)
			(layer "F.Fab")
			(hide yes)
			(effects
				(font
					(size 1 1)
					(thickness 0.15)
				)
			)
		)
		(property "Author" "Antmicro"
			(at 0 0 90)
			(unlocked yes)
			(layer "F.Fab")
			(hide yes)
			(effects
				(font
					(size 1 1)
					(thickness 0.15)
				)
			)
		)
		(property "License" "Apache-2.0"
			(at 0 0 90)
			(unlocked yes)
			(layer "F.Fab")
			(hide yes)
			(effects
				(font
					(size 1 1)
					(thickness 0.15)
				)
			)
		)
		(property "Color" "R, G, B"
			(at 0 0 90)
			(unlocked yes)
			(layer "F.Fab")
			(hide yes)
			(effects
				(font
					(size 1 1)
					(thickness 0.15)
				)
			)
		)
		(sheetname "/FPGA GPIO/")
		(sheetfile "fpga-gpio.kicad_sch")
		(attr smd)
		(fp_circle
			(center 1 -0.805)
			(end 1.05 -0.805)
			(stroke
				(width 0.15)
				(type solid)
			)
			(fill yes)
			(layer "F.SilkS")
		)
		(fp_rect
			(start -2.75 -1.145)
			(end 2.75 1.495)
			(stroke
				(width 0.05)
				(type solid)
			)
			(fill no)
			(layer "F.CrtYd")
		)
		(fp_text user "${REFERENCE}"
			(at -2.75 3.495 90)
			(unlocked yes)
			(layer "F.Fab")
			(effects
				(font
					(size 0.7 0.7)
					(thickness 0.15)
				)
				(justify left bottom)
			)
		)
		(fp_text user "Author: Antmicro"
			(at -2.75 5.895 90)
			(layer "F.Fab")
			(effects
				(font
					(size 0.7 0.7)
					(thickness 0.15)
				)
				(justify left bottom)
			)
		)
		(fp_text user "License: Apache-2.0"
			(at -2.75 4.695 90)
			(layer "F.Fab")
			(effects
				(font
					(size 0.7 0.7)
					(thickness 0.15)
				)
				(justify left bottom)
			)
		)
		(pad "1" smd roundrect
			(at 0.4 -0.5 90)
			(size 0.5 0.8)
			(layers "F.Cu" "F.Mask" "F.Paste")
			(roundrect_rratio 0.1)
			(net 385 "Net-(D6-C_{R})")
			(pinfunction "C_{R}")
			(pintype "passive")
		)
		(pad "2" smd roundrect
			(at -0.4 -0.5 90)
			(size 0.5 0.8)
			(layers "F.Cu" "F.Mask" "F.Paste")
			(roundrect_rratio 0.1)
			(net 538 "Net-(D6-C_{G})")
			(pinfunction "C_{G}")
			(pintype "passive")
		)
		(pad "3" smd roundrect
			(at -1.75 0 90)
			(size 1.5 1)
			(layers "F.Cu" "F.Mask" "F.Paste")
			(roundrect_rratio 0.05)
			(net 539 "Net-(D6-C_{B})")
			(pinfunction "C_{B}")
			(pintype "passive")
		)
		(pad "4" smd roundrect
			(at 1.75 0 90)
			(size 1.5 1)
			(layers "F.Cu" "F.Mask" "F.Paste")
			(roundrect_rratio 0.05)
			(net 90 "+5V")
			(pinfunction "A")
			(pintype "passive")
		)
	)
	(footprint "antmicro-footprints:VQFN-14-1EP_3.2x2.5mm_P0.5mm_Layout4x3"
		(layer "F.Cu")
		(at 221.23 153.085 -90)
		(property "Reference" "U17"
			(at 0.465 2.174 90)
			(unlocked yes)
			(layer "F.SilkS")
			(effects
				(font
					(size 0.7 0.7)
					(thickness 0.15)
				)
				(justify left bottom)
			)
		)
		(property "Value" "DSC557-0343FI1"
			(at 0 3.1 270)
			(unlocked yes)
			(layer "F.Fab")
			(hide yes)
			(effects
				(font
					(size 0.7 0.7)
					(thickness 0.15)
				)
				(justify left bottom)
			)
		)
		(property "Datasheet" "https://ww1.microchip.com/downloads/aemDocuments/documents/TCG/ProductDocuments/DataSheets/DSC557-03-04-05-Multiple-Output-MEMS-PCIe-Gen1-2-3-4-Clock-Generators-DS20006691.pdf"
			(at 0 0 90)
			(layer "F.Fab")
			(hide yes)
			(effects
				(font
					(size 1.27 1.27)
					(thickness 0.15)
				)
			)
		)
		(property "Description" "Two output PCIe Clock Generator"
			(at 0 0 90)
			(layer "F.Fab")
			(hide yes)
			(effects
				(font
					(size 1.27 1.27)
					(thickness 0.15)
				)
			)
		)
		(property "Author" "Antmicro"
			(at 68.159 374.329 0)
			(layer "F.Fab")
			(hide yes)
			(effects
				(font
					(size 1 1)
					(thickness 0.15)
				)
			)
		)
		(property "License" "Apache-2.0"
			(at 68.159 374.329 0)
			(layer "F.Fab")
			(hide yes)
			(effects
				(font
					(size 1 1)
					(thickness 0.15)
				)
			)
		)
		(property "MPN" "DSC557-0343FI1"
			(at 68.159 374.329 0)
			(layer "F.Fab")
			(hide yes)
			(effects
				(font
					(size 1 1)
					(thickness 0.15)
				)
			)
		)
		(property "Manufacturer" "Microchip Technology"
			(at 68.159 374.329 0)
			(layer "F.Fab")
			(hide yes)
			(effects
				(font
					(size 1 1)
					(thickness 0.15)
				)
			)
		)
		(property "Val" "100 MHz"
			(at 68.159 374.329 0)
			(layer "F.Fab")
			(hide yes)
			(effects
				(font
					(size 1 1)
					(thickness 0.15)
				)
			)
		)
		(property ki_fp_filters "QFN14_3.2X2.5_MCH QFN14_3.2X2.5_MCH-M QFN14_3.2X2.5_MCH-L")
		(sheetname "/PCIe/")
		(sheetfile "pcie.kicad_sch")
		(attr smd)
		(fp_circle
			(center -1.5 -1.075)
			(end -1.45 -1.075)
			(stroke
				(width 0.15)
				(type solid)
			)
			(fill yes)
			(layer "F.SilkS")
		)
		(fp_rect
			(start -1.746 -2.101)
			(end 1.745 2.1)
			(stroke
				(width 0.05)
				(type solid)
			)
			(fill no)
			(layer "F.CrtYd")
		)
		(fp_line
			(start -1.266 1.677)
			(end 1.269 1.677)
			(stroke
				(width 0.15)
				(type solid)
			)
			(layer "F.Fab")
		)
		(fp_line
			(start -1.266 1.677)
			(end -1.266 -1.067)
			(stroke
				(width 0.15)
				(type solid)
			)
			(layer "F.Fab")
		)
		(fp_line
			(start 1.269 1.677)
			(end 1.269 -1.625)
			(stroke
				(width 0.15)
				(type solid)
			)
			(layer "F.Fab")
		)
		(fp_line
			(start -1.266 -1.067)
			(end -0.758 -1.625)
			(stroke
				(width 0.15)
				(type solid)
			)
			(layer "F.Fab")
		)
		(fp_line
			(start 1.269 -1.625)
			(end -0.758 -1.625)
			(stroke
				(width 0.15)
				(type solid)
			)
			(layer "F.Fab")
		)
		(fp_text user "License: Apache-2.0"
			(at -1.746 7.499 270)
			(layer "F.Fab")
			(effects
				(font
					(size 0.7 0.7)
					(thickness 0.15)
				)
				(justify left bottom)
			)
		)
		(fp_text user "Author: Antmicro"
			(at -1.746 6.299 270)
			(layer "F.Fab")
			(effects
				(font
					(size 0.7 0.7)
					(thickness 0.15)
				)
				(justify left bottom)
			)
		)
		(fp_text user "${REFERENCE}"
			(at -1.746 5.099 270)
			(unlocked yes)
			(layer "F.Fab")
			(effects
				(font
					(size 0.7 0.7)
					(thickness 0.15)
				)
				(justify left bottom)
			)
		)
		(pad "1" smd rect
			(at -1.3 -0.762)
			(size 0.3 0.7)
			(layers "F.Cu" "F.Mask" "F.Paste")
			(net 418 "+2V5")
			(pinfunction "OE")
			(pintype "input")
		)
		(pad "2" smd rect
			(at -1.3 -0.25)
			(size 0.3 0.7)
			(layers "F.Cu" "F.Mask" "F.Paste")
			(net 569 "unconnected-(U17-NC-Pad2)")
			(pinfunction "NC")
			(pintype "no_connect")
		)
		(pad "3" smd rect
			(at -1.3 0.25)
			(size 0.3 0.7)
			(layers "F.Cu" "F.Mask" "F.Paste")
			(net 570 "unconnected-(U17-NC-Pad3)")
			(pinfunction "NC")
			(pintype "no_connect")
		)
		(pad "4" smd rect
			(at -1.3 0.75)
			(size 0.3 0.7)
			(layers "F.Cu" "F.Mask" "F.Paste")
			(net 417 "GND")
			(pinfunction "VSS")
			(pintype "power_in")
		)
		(pad "5" smd rect
			(at -0.5 1.65 270)
			(size 0.3 0.7)
			(layers "F.Cu" "F.Mask" "F.Paste")
			(net 571 "unconnected-(U17-NC-Pad5)")
			(pinfunction "NC")
			(pintype "no_connect")
		)
		(pad "6" smd rect
			(at 0 1.65 270)
			(size 0.3 0.7)
			(layers "F.Cu" "F.Mask" "F.Paste")
			(net 572 "unconnected-(U17-NC-Pad6)")
			(pinfunction "NC")
			(pintype "no_connect")
		)
		(pad "7" smd rect
			(at 0.5 1.65 270)
			(size 0.3 0.7)
			(layers "F.Cu" "F.Mask" "F.Paste")
			(net 573 "unconnected-(U17-NC-Pad7)")
			(pinfunction "NC")
			(pintype "no_connect")
		)
		(pad "8" smd rect
			(at 1.3 0.75 180)
			(size 0.3 0.7)
			(layers "F.Cu" "F.Mask" "F.Paste")
			(net 315 "Net-(U17-CLK1+)")
			(pinfunction "CLK1+")
			(pintype "output")
		)
		(pad "9" smd rect
			(at 1.3 0.25 180)
			(size 0.3 0.7)
			(layers "F.Cu" "F.Mask" "F.Paste")
			(net 314 "Net-(U17-CLK1-)")
			(pinfunction "CLK1-")
			(pintype "output")
		)
		(pad "10" smd rect
			(at 1.3 -0.25 180)
			(size 0.3 0.7)
			(layers "F.Cu" "F.Mask" "F.Paste")
			(net 562 "/PCIe/PF_PCIe_CLK_N")
			(pinfunction "CLK0-")
			(pintype "output")
		)
		(pad "11" smd rect
			(at 1.3 -0.75 180)
			(size 0.3 0.7)
			(layers "F.Cu" "F.Mask" "F.Paste")
			(net 461 "/PCIe/PF_PCIe_CLK_P")
			(pinfunction "CLK0+")
			(pintype "output")
		)
		(pad "12" smd rect
			(at 0.5 -1.65 90)
			(size 0.3 0.7)
			(layers "F.Cu" "F.Mask" "F.Paste")
			(net 418 "+2V5")
			(pinfunction "VDD1")
			(pintype "power_in")
		)
		(pad "13" smd rect
			(at 0 -1.65 90)
			(size 0.3 0.7)
			(layers "F.Cu" "F.Mask" "F.Paste")
			(net 418 "+2V5")
			(pinfunction "VDD0")
			(pintype "power_in")
		)
		(pad "14" smd rect
			(at -0.5 -1.65 90)
			(size 0.3 0.7)
			(layers "F.Cu" "F.Mask" "F.Paste")
			(net 574 "unconnected-(U17-NC-Pad14)")
			(pinfunction "NC")
			(pintype "no_connect")
		)
		(pad "15" smd roundrect
			(at 0.003 0)
			(size 2.1 1.4)
			(layers "F.Cu" "F.Mask" "F.Paste")
			(roundrect_rratio 0)
			(chamfer_ratio 0.2)
			(chamfer top_right)
			(net 417 "GND")
			(pinfunction "EPAD")
			(pintype "unspecified")
		)
	)
	(footprint "antmicro-footprints:R_0402_1005Metric"
		(layer "F.Cu")
		(at 214.185 139.2 180)
		(descr "Resistor SMD 0402")
		(tags "resistor SMD 0402")
		(property "Reference" "R58"
			(at -3.265 -0.41 180)
			(layer "F.SilkS")
			(effects
				(font
					(size 0.7 0.7)
					(thickness 0.15)
				)
				(justify left bottom)
			)
		)
		(property "Value" "R_1k_0402"
			(at -1.011843 1.772047 180)
			(layer "F.Fab")
			(hide yes)
			(effects
				(font
					(size 0.7 0.7)
					(thickness 0.15)
				)
				(justify left bottom)
			)
		)
		(property "Datasheet" "https://www.bourns.com/docs/product-datasheets/cr.pdf"
			(at 0 0 180)
			(layer "F.Fab")
			(hide yes)
			(effects
				(font
					(size 1.27 1.27)
					(thickness 0.15)
				)
			)
		)
		(property "Description" "SMD Chip Resistor, 1 kohm, ± 1%, 63 mW, 0402 [1005 Metric], Thick Film, General Purpose"
			(at 0 0 180)
			(layer "F.Fab")
			(hide yes)
			(effects
				(font
					(size 1.27 1.27)
					(thickness 0.15)
				)
			)
		)
		(property "Author" "Antmicro"
			(at 428.37 278.4 0)
			(layer "F.Fab")
			(hide yes)
			(effects
				(font
					(size 1 1)
					(thickness 0.15)
				)
			)
		)
		(property "DNP" "DNP"
			(at 428.37 278.4 0)
			(layer "F.Fab")
			(hide yes)
			(effects
				(font
					(size 1 1)
					(thickness 0.15)
				)
			)
		)
		(property "License" "Apache-2.0"
			(at 428.37 278.4 0)
			(layer "F.Fab")
			(hide yes)
			(effects
				(font
					(size 1 1)
					(thickness 0.15)
				)
			)
		)
		(property "MPN" "CR0402-FX-1001GLF"
			(at 428.37 278.4 0)
			(layer "F.Fab")
			(hide yes)
			(effects
				(font
					(size 1 1)
					(thickness 0.15)
				)
			)
		)
		(property "Manufacturer" "Bourns"
			(at 428.37 278.4 0)
			(layer "F.Fab")
			(hide yes)
			(effects
				(font
					(size 1 1)
					(thickness 0.15)
				)
			)
		)
		(property "Public" ""
			(at 428.37 278.4 0)
			(layer "F.Fab")
			(hide yes)
			(effects
				(font
					(size 1 1)
					(thickness 0.15)
				)
			)
		)
		(property "Tolerance" "1%"
			(at 428.37 278.4 0)
			(layer "F.Fab")
			(hide yes)
			(effects
				(font
					(size 1 1)
					(thickness 0.15)
				)
			)
		)
		(property "Val" "1k"
			(at 428.37 278.4 0)
			(layer "F.Fab")
			(hide yes)
			(effects
				(font
					(size 1 1)
					(thickness 0.15)
				)
			)
		)
		(sheetname "/USB/")
		(sheetfile "usb.kicad_sch")
		(attr smd dnp)
		(fp_rect
			(start -0.925 -0.47)
			(end 0.925 0.47)
			(stroke
				(width 0.05)
				(type default)
			)
			(fill no)
			(layer "F.CrtYd")
		)
		(fp_rect
			(start -0.5 -0.25)
			(end 0.5 0.25)
			(stroke
				(width 0.15)
				(type solid)
			)
			(fill no)
			(layer "F.Fab")
		)
		(fp_text user "Author: Antmicro"
			(at -0.95 4.169 180)
			(layer "F.Fab")
			(effects
				(font
					(size 0.7 0.7)
					(thickness 0.15)
				)
				(justify left bottom)
			)
		)
		(fp_text user "License: Apache-2.0"
			(at -0.95 5.169 180)
			(layer "F.Fab")
			(effects
				(font
					(size 0.7 0.7)
					(thickness 0.15)
				)
				(justify left bottom)
			)
		)
		(fp_text user "${REFERENCE}"
			(at -0.95 3.168 180)
			(layer "F.Fab")
			(effects
				(font
					(size 0.7 0.7)
					(thickness 0.15)
				)
				(justify left bottom)
			)
		)
		(pad "1" smd roundrect
			(at -0.48 0 180)
			(size 0.59 0.64)
			(layers "F.Cu" "F.Mask" "F.Paste")
			(roundrect_rratio 0.25)
			(net 417 "GND")
			(pintype "passive")
		)
		(pad "2" smd roundrect
			(at 0.48 0 180)
			(size 0.59 0.64)
			(layers "F.Cu" "F.Mask" "F.Paste")
			(roundrect_rratio 0.25)
			(net 221 "VBUS")
			(pintype "passive")
		)
	)
	(footprint "antmicro-footprints:FB_0402_1005Metric"
		(layer "F.Cu")
		(at 208.085 144.825)
		(descr "Ferrite Bead SMD 0402")
		(tags "ferrite bead SMD 0402")
		(property "Reference" "FB3"
			(at -7.11 9.49 90)
			(layer "F.SilkS")
			(effects
				(font
					(size 0.7 0.7)
					(thickness 0.15)
				)
				(justify left bottom)
			)
		)
		(property "Value" "FB_120Z_1.2A_TDK-MPZ_0402"
			(at 0 1.4 0)
			(layer "F.Fab")
			(hide yes)
			(effects
				(font
					(size 0.7 0.7)
					(thickness 0.15)
				)
				(justify left bottom)
			)
		)
		(property "Datasheet" "https://product.tdk.com/en/search/emc/emc/beads/info?part_no=MPZ1005S121CT000"
			(at 0 0 0)
			(layer "F.Fab")
			(hide yes)
			(effects
				(font
					(size 1.27 1.27)
					(thickness 0.15)
				)
			)
		)
		(property "Description" "Ferrite Bead, 0402 [1005 Metric], 120 ohm, 1.2A, MPZ, 0.06 ohm, ± 25%, DC Power line"
			(at 0 0 0)
			(layer "F.Fab")
			(hide yes)
			(effects
				(font
					(size 1.27 1.27)
					(thickness 0.15)
				)
			)
		)
		(property "Author" "Antmicro"
			(at 0 0 0)
			(layer "F.Fab")
			(hide yes)
			(effects
				(font
					(size 1 1)
					(thickness 0.15)
				)
			)
		)
		(property "Current" ""
			(at 0 0 0)
			(layer "F.Fab")
			(hide yes)
			(effects
				(font
					(size 1 1)
					(thickness 0.15)
				)
			)
		)
		(property "License" "Apache-2.0"
			(at 0 0 0)
			(layer "F.Fab")
			(hide yes)
			(effects
				(font
					(size 1 1)
					(thickness 0.15)
				)
			)
		)
		(property "MPN" "MPZ1005S121CT000"
			(at 0 0 0)
			(layer "F.Fab")
			(hide yes)
			(effects
				(font
					(size 1 1)
					(thickness 0.15)
				)
			)
		)
		(property "Manufacturer" "TDK"
			(at 0 0 0)
			(layer "F.Fab")
			(hide yes)
			(effects
				(font
					(size 1 1)
					(thickness 0.15)
				)
			)
		)
		(property "Public" ""
			(at 0 0 0)
			(layer "F.Fab")
			(hide yes)
			(effects
				(font
					(size 1 1)
					(thickness 0.15)
				)
			)
		)
		(property "Val" "120Z/1.2A"
			(at 0 0 0)
			(layer "F.Fab")
			(hide yes)
			(effects
				(font
					(size 1 1)
					(thickness 0.15)
				)
			)
		)
		(sheetname "/MIPI CrossLink/")
		(sheetfile "crosslink.kicad_sch")
		(attr smd)
		(fp_rect
			(start -0.925 -0.47)
			(end 0.925 0.47)
			(stroke
				(width 0.05)
				(type default)
			)
			(fill no)
			(layer "F.CrtYd")
		)
		(fp_rect
			(start -0.5 -0.25)
			(end 0.5 0.25)
			(stroke
				(width 0.15)
				(type solid)
			)
			(fill no)
			(layer "F.Fab")
		)
		(fp_text user "License: Apache-2.0"
			(at -0.95 5.169 0)
			(layer "F.Fab")
			(effects
				(font
					(size 0.7 0.7)
					(thickness 0.15)
				)
				(justify left bottom)
			)
		)
		(fp_text user "Author: Antmicro"
			(at -0.95 4.169 0)
			(layer "F.Fab")
			(effects
				(font
					(size 0.7 0.7)
					(thickness 0.15)
				)
				(justify left bottom)
			)
		)
		(fp_text user "${REFERENCE}"
			(at -0.95 3.168 0)
			(layer "F.Fab")
			(effects
				(font
					(size 0.7 0.7)
					(thickness 0.15)
				)
				(justify left bottom)
			)
		)
		(pad "1" smd roundrect
			(at -0.48 0)
			(size 0.59 0.64)
			(layers "F.Cu" "F.Mask" "F.Paste")
			(roundrect_rratio 0.25)
			(net 180 "/MIPI CrossLink/CL_VCCGPLL")
			(pintype "passive")
		)
		(pad "2" smd roundrect
			(at 0.48 0)
			(size 0.59 0.64)
			(layers "F.Cu" "F.Mask" "F.Paste")
			(roundrect_rratio 0.25)
			(net 96 "+1V2")
			(pintype "passive")
		)
	)
)
